(kicad_pcb
	(version 20260206)
	(generator "pcbnew")
	(generator_version "10.0")
	(general
		(thickness 1.6)
		(legacy_teardrops no)
	)
	(paper "A4")
	(title_block
		(title "v1-tray-backplane — T6M_tray_BP_c_1023_1120.brd")
		(comment 1 "Open CloudServer (Microsoft) / footprints 165-170 of 170")
	)
	(layers
		(0 "F.Cu" signal "TOP")
		(4 "In1.Cu" signal "GND")
		(6 "In2.Cu" signal "IN1")
		(8 "In3.Cu" signal "VCC")
		(10 "In4.Cu" signal "VCC1")
		(12 "In5.Cu" signal "IN2")
		(14 "In6.Cu" signal "GND1")
		(2 "B.Cu" signal "BOTTOM")
		(9 "F.Adhes" user "F.Adhesive")
		(11 "B.Adhes" user "B.Adhesive")
		(13 "F.Paste" user "Package Geometry/Pastemask Top")
		(15 "B.Paste" user "Package Geometry/Pastemask Bottom")
		(5 "F.SilkS" user "Ref Des/Silkscreen Top")
		(7 "B.SilkS" user "Ref Des/Silkscreen Bottom")
		(1 "F.Mask" user "Board Geometry/Soldermask Top")
		(3 "B.Mask" user "Board Geometry/Soldermask Bottom")
		(17 "Dwgs.User" user "User.Drawings")
		(19 "Cmts.User" user "User.Comments")
		(21 "Eco1.User" user "User.Eco1")
		(23 "Eco2.User" user "User.Eco2")
		(25 "Edge.Cuts" user "Board Geometry/Outline")
		(27 "Margin" user)
		(31 "F.CrtYd" user "Package Geometry/Place Bound Top")
		(29 "B.CrtYd" user "Package Geometry/Place Bound Bottom")
		(35 "F.Fab" user "Ref Des/Assembly Top")
		(33 "B.Fab" user "Ref Des/Assembly Bottom")
	)
	(footprint ""
		(layer "F.Cu")
		(at 367.538 -3.1242 90)
		(property "Reference" "C26"
			(at -2.3368 2.194052 90)
			(unlocked yes)
			(layer "F.SilkS")
			(effects
				(font
					(size 0.7874 0.5842)
					(thickness 0.1524)
				)
				(justify left)
			)
		)
		(property "Value" ""
			(at 0 0 90)
			(layer "F.Fab")
			(effects
				(font
					(size 1.27 1.27)
				)
			)
		)
		(duplicate_pad_numbers_are_jumpers no)
		(fp_line
			(start 0.7874 -0.4064)
			(end 0.7874 0.4064)
			(stroke
				(width 0.1524)
				(type default)
			)
			(layer "F.SilkS")
		)
		(fp_line
			(start -0.7874 -0.4064)
			(end 0.7874 -0.4064)
			(stroke
				(width 0.1524)
				(type default)
			)
			(layer "F.SilkS")
		)
		(fp_line
			(start 0 0.381)
			(end 0 -0.381)
			(stroke
				(width 0.1524)
				(type default)
			)
			(layer "F.SilkS")
		)
		(fp_line
			(start 0.7874 0.4064)
			(end -0.7874 0.4064)
			(stroke
				(width 0.1524)
				(type default)
			)
			(layer "F.SilkS")
		)
		(fp_line
			(start -0.7874 0.4064)
			(end -0.7874 -0.4064)
			(stroke
				(width 0.1524)
				(type default)
			)
			(layer "F.SilkS")
		)
		(fp_poly
			(pts
				(xy -0.5334 0.254) (xy -0.635 0.254) (xy -0.635 0.2286) (xy -0.635 -0.254) (xy -0.5334 -0.254) (xy -0.5334 -0.2794)
				(xy 0.5334 -0.2794) (xy 0.5334 -0.254) (xy 0.635 -0.254) (xy 0.635 0.254) (xy 0.5334 0.254) (xy 0.5334 0.2794)
				(xy -0.508 0.2794) (xy -0.5334 0.2794)
			)
			(stroke
				(width 0)
				(type default)
			)
			(fill no)
			(layer "F.CrtYd")
		)
		(pad "1" smd rect
			(at 0.40005 0 90)
			(size 0.4572 0.508)
			(layers "F.Cu" "F.Mask" "F.Paste")
			(net "P3V3_10G_3_VCCT")
		)
		(pad "2" smd rect
			(at -0.40005 0 90)
			(size 0.4572 0.508)
			(layers "F.Cu" "F.Mask" "F.Paste")
			(net "GND")
		)
	)
	(footprint ""
		(layer "F.Cu")
		(at 28.437332 -19.7358 -90)
		(property "Reference" "R84"
			(at 0.9144 -5.110988 90)
			(unlocked yes)
			(layer "F.SilkS")
			(effects
				(font
					(size 0.7874 0.5842)
					(thickness 0.1524)
				)
				(justify left)
			)
		)
		(property "Value" ""
			(at 0 0 270)
			(layer "F.Fab")
			(effects
				(font
					(size 1.27 1.27)
				)
			)
		)
		(duplicate_pad_numbers_are_jumpers no)
		(fp_line
			(start -0.7874 0.4064)
			(end -0.7874 -0.4064)
			(stroke
				(width 0.1524)
				(type default)
			)
			(layer "F.SilkS")
		)
		(fp_line
			(start 0.7874 0.4064)
			(end -0.7874 0.4064)
			(stroke
				(width 0.1524)
				(type default)
			)
			(layer "F.SilkS")
		)
		(fp_line
			(start -0.7874 -0.4064)
			(end 0.7874 -0.4064)
			(stroke
				(width 0.1524)
				(type default)
			)
			(layer "F.SilkS")
		)
		(fp_line
			(start 0.7874 -0.4064)
			(end 0.7874 0.4064)
			(stroke
				(width 0.1524)
				(type default)
			)
			(layer "F.SilkS")
		)
		(fp_poly
			(pts
				(xy -0.508 0.2794) (xy -0.508 0.2286) (xy -0.635 0.2286) (xy -0.635 -0.254) (xy -0.5334 -0.254)
				(xy -0.5334 -0.2794) (xy 0.5334 -0.2794) (xy 0.5334 -0.254) (xy 0.635 -0.254) (xy 0.635 0.254) (xy 0.5334 0.254)
				(xy 0.5334 0.2794)
			)
			(stroke
				(width 0)
				(type default)
			)
			(fill no)
			(layer "F.CrtYd")
		)
		(pad "1" smd rect
			(at 0.40005 0 270)
			(size 0.4572 0.508)
			(layers "F.Cu" "F.Mask" "F.Paste")
			(net "N39386877")
		)
		(pad "2" smd rect
			(at -0.40005 0 270)
			(size 0.4572 0.508)
			(layers "F.Cu" "F.Mask" "F.Paste")
			(net "P12V")
		)
	)
	(footprint ""
		(layer "F.Cu")
		(at 313.07024 -30.368494)
		(property "Reference" "R18"
			(at -6.5532 -0.676148 0)
			(unlocked yes)
			(layer "F.SilkS")
			(effects
				(font
					(size 0.7874 0.5842)
					(thickness 0.1524)
				)
				(justify left)
			)
		)
		(property "Value" ""
			(at 0 0 0)
			(layer "F.Fab")
			(effects
				(font
					(size 1.27 1.27)
				)
			)
		)
		(duplicate_pad_numbers_are_jumpers no)
		(fp_line
			(start -0.7874 -0.4064)
			(end 0.7874 -0.4064)
			(stroke
				(width 0.1524)
				(type default)
			)
			(layer "F.SilkS")
		)
		(fp_line
			(start -0.7874 0.4064)
			(end -0.7874 -0.4064)
			(stroke
				(width 0.1524)
				(type default)
			)
			(layer "F.SilkS")
		)
		(fp_line
			(start 0.7874 -0.4064)
			(end 0.7874 0.4064)
			(stroke
				(width 0.1524)
				(type default)
			)
			(layer "F.SilkS")
		)
		(fp_line
			(start 0.7874 0.4064)
			(end -0.7874 0.4064)
			(stroke
				(width 0.1524)
				(type default)
			)
			(layer "F.SilkS")
		)
		(fp_poly
			(pts
				(xy -0.508 0.2794) (xy -0.508 0.2286) (xy -0.635 0.2286) (xy -0.635 -0.254) (xy -0.5334 -0.254)
				(xy -0.5334 -0.2794) (xy 0.5334 -0.2794) (xy 0.5334 -0.254) (xy 0.635 -0.254) (xy 0.635 0.254) (xy 0.5334 0.254)
				(xy 0.5334 0.2794)
			)
			(stroke
				(width 0)
				(type default)
			)
			(fill no)
			(layer "F.CrtYd")
		)
		(pad "1" smd rect
			(at 0.40005 0)
			(size 0.4572 0.508)
			(layers "F.Cu" "F.Mask" "F.Paste")
			(net "P3V3_BLAD2")
		)
		(pad "2" smd rect
			(at -0.40005 0)
			(size 0.4572 0.508)
			(layers "F.Cu" "F.Mask" "F.Paste")
			(net "ENET10G_4_TX_FAULT")
		)
	)
	(footprint ""
		(layer "F.Cu")
		(at 375.82856 -24.906478 180)
		(property "Reference" "R19"
			(at -33.81248 -16.726408 0)
			(unlocked yes)
			(layer "F.SilkS")
			(effects
				(font
					(size 0.7874 0.5842)
					(thickness 0.1524)
				)
				(justify left)
			)
		)
		(property "Value" ""
			(at 0 0 180)
			(layer "F.Fab")
			(effects
				(font
					(size 1.27 1.27)
				)
			)
		)
		(duplicate_pad_numbers_are_jumpers no)
		(fp_line
			(start 0.7874 0.4064)
			(end -0.7874 0.4064)
			(stroke
				(width 0.1524)
				(type default)
			)
			(layer "F.SilkS")
		)
		(fp_line
			(start 0.7874 -0.4064)
			(end 0.7874 0.4064)
			(stroke
				(width 0.1524)
				(type default)
			)
			(layer "F.SilkS")
		)
		(fp_line
			(start -0.7874 0.4064)
			(end -0.7874 -0.4064)
			(stroke
				(width 0.1524)
				(type default)
			)
			(layer "F.SilkS")
		)
		(fp_line
			(start -0.7874 -0.4064)
			(end 0.7874 -0.4064)
			(stroke
				(width 0.1524)
				(type default)
			)
			(layer "F.SilkS")
		)
		(fp_poly
			(pts
				(xy -0.508 0.2794) (xy -0.508 0.2286) (xy -0.635 0.2286) (xy -0.635 -0.254) (xy -0.5334 -0.254)
				(xy -0.5334 -0.2794) (xy 0.5334 -0.2794) (xy 0.5334 -0.254) (xy 0.635 -0.254) (xy 0.635 0.254) (xy 0.5334 0.254)
				(xy 0.5334 0.2794)
			)
			(stroke
				(width 0)
				(type default)
			)
			(fill no)
			(layer "F.CrtYd")
		)
		(pad "1" smd rect
			(at 0.40005 0 180)
			(size 0.4572 0.508)
			(layers "F.Cu" "F.Mask" "F.Paste")
			(net "P3V3_BLAD2")
		)
		(pad "2" smd rect
			(at -0.40005 0 180)
			(size 0.4572 0.508)
			(layers "F.Cu" "F.Mask" "F.Paste")
			(net "ENET10G_3_TX_DIS")
		)
	)
	(footprint ""
		(layer "F.Cu")
		(at 84.328 -33.7058 90)
		(property "Reference" "L2"
			(at -0.6096 -2.56413 90)
			(unlocked yes)
			(layer "F.SilkS")
			(effects
				(font
					(size 0.7874 0.5842)
					(thickness 0.1524)
				)
				(justify left)
			)
		)
		(property "Value" ""
			(at 0 0 90)
			(layer "F.Fab")
			(effects
				(font
					(size 1.27 1.27)
				)
			)
		)
		(duplicate_pad_numbers_are_jumpers no)
		(fp_line
			(start -1.905 -0.8636)
			(end 1.905 -0.8636)
			(stroke
				(width 0.1524)
				(type default)
			)
			(layer "F.SilkS")
		)
		(fp_line
			(start 1.905 0.8382)
			(end 1.905 -0.8382)
			(stroke
				(width 0.1524)
				(type default)
			)
			(layer "F.SilkS")
		)
		(fp_line
			(start 0.127 0.8382)
			(end 0.127 -0.8382)
			(stroke
				(width 0.1524)
				(type default)
			)
			(layer "F.SilkS")
		)
		(fp_line
			(start -0.127 0.8382)
			(end -0.127 -0.8382)
			(stroke
				(width 0.1524)
				(type default)
			)
			(layer "F.SilkS")
		)
		(fp_line
			(start -1.905 0.8382)
			(end -1.905 -0.8382)
			(stroke
				(width 0.1524)
				(type default)
			)
			(layer "F.SilkS")
		)
		(fp_line
			(start 1.905 0.8636)
			(end -1.905 0.8636)
			(stroke
				(width 0.1524)
				(type default)
			)
			(layer "F.SilkS")
		)
		(fp_rect
			(start -1.524 0.7112)
			(end 1.524 -0.7366)
			(stroke
				(width 0)
				(type default)
			)
			(fill no)
			(layer "F.CrtYd")
		)
		(pad "1" smd rect
			(at 0.94996 0 90)
			(size 1.1176 1.3716)
			(layers "F.Cu" "F.Mask" "F.Paste")
			(net "P3V3_10G_2_VCCT_L")
		)
		(pad "2" smd rect
			(at -0.94996 0 90)
			(size 1.1176 1.3716)
			(layers "F.Cu" "F.Mask" "F.Paste")
			(net "P3V3_10G_2_VCCT")
		)
	)
	(footprint ""
		(layer "B.Cu")
		(at 425.809918 -26.100024)
		(property "Reference" "GNDPAD2"
			(at -3.542284 6.335268 270)
			(unlocked yes)
			(layer "B.SilkS")
			(effects
				(font
					(size 0.7874 0.5842)
					(thickness 0.1524)
				)
				(justify left mirror)
			)
		)
		(property "Value" ""
			(at 0 0 0)
			(layer "B.Fab")
			(effects
				(font
					(size 1.27 1.27)
				)
				(justify mirror)
			)
		)
		(duplicate_pad_numbers_are_jumpers no)
		(fp_poly
			(pts
				(xy 1.3589 5.461) (xy -1.3589 5.461) (xy -1.3589 -5.461) (xy 1.3589 -5.461)
			)
			(stroke
				(width 0)
				(type default)
			)
			(fill no)
			(layer "B.CrtYd")
		)
		(pad "1" smd rect
			(at 0 0 180)
			(size 2.6162 10.8204)
			(layers "B.Cu" "B.Mask" "B.Paste")
			(net "GND")
		)
	)
)
